(kicad_pcb
	(version 20260206)
	(generator "pcbnew")
	(generator_version "10.0")
	(general
		(thickness 1.6)
		(legacy_teardrops no)
	)
	(paper "A4")
	(title_block
		(title "03242023_DA0F0TMBIJ0_F0T_Motherboard_J_brd_V01_OCP.brd")
		(comment 1 "Grand Teton / footprints 1181-1184 of 6105")
	)
	(layers
		(0 "F.Cu" signal "TOP")
		(4 "In1.Cu" signal "GND")
		(6 "In2.Cu" signal "IN1")
		(8 "In3.Cu" signal "GND1")
		(10 "In4.Cu" signal "IN2")
		(12 "In5.Cu" signal "GND2")
		(14 "In6.Cu" signal "IN3")
		(16 "In7.Cu" signal "GND3")
		(18 "In8.Cu" signal "VCC")
		(20 "In9.Cu" signal "VCC1")
		(22 "In10.Cu" signal "GND4")
		(24 "In11.Cu" signal "IN4")
		(26 "In12.Cu" signal "GND5")
		(28 "In13.Cu" signal "IN5")
		(30 "In14.Cu" signal "GND6")
		(32 "In15.Cu" signal "IN6")
		(34 "In16.Cu" signal "GND7")
		(2 "B.Cu" signal "BOTTOM")
		(9 "F.Adhes" user "F.Adhesive")
		(11 "B.Adhes" user "B.Adhesive")
		(13 "F.Paste" user "Package Geometry/Pastemask Top")
		(15 "B.Paste" user "Package Geometry/Pastemask Bottom")
		(5 "F.SilkS" user "Ref Des/Silkscreen Top")
		(7 "B.SilkS" user "Ref Des/Silkscreen Bottom")
		(1 "F.Mask" user "Board Geometry/Soldermask Top")
		(3 "B.Mask" user "Board Geometry/Soldermask Bottom")
		(17 "Dwgs.User" user "User.Drawings")
		(19 "Cmts.User" user "User.Comments")
		(21 "Eco1.User" user "User.Eco1")
		(23 "Eco2.User" user "User.Eco2")
		(25 "Edge.Cuts" user "Board Geometry/Outline")
		(27 "Margin" user)
		(31 "F.CrtYd" user "Package Geometry/Place Bound Top")
		(29 "B.CrtYd" user "Package Geometry/Place Bound Bottom")
		(35 "F.Fab" user "Ref Des/Assembly Top")
		(33 "B.Fab" user "Ref Des/Assembly Bottom")
	)
	(footprint ""
		(layer "F.Cu")
		(at 200.172066 -402.722842 180)
		(property "Reference" "PU287"
			(at 0.468376 7.808468 0)
			(unlocked yes)
			(layer "F.SilkS")
			(effects
				(font
					(size 0.7874 0.5842)
					(thickness 0.1524)
				)
			)
		)
		(property "Value" ""
			(at 0 0 180)
			(layer "F.Fab")
			(effects
				(font
					(size 1.27 1.27)
				)
			)
		)
		(duplicate_pad_numbers_are_jumpers no)
		(fp_line
			(start 2.567686 2.567686)
			(end 2.567686 -2.567686)
			(stroke
				(width 0.1524)
				(type default)
			)
			(layer "F.SilkS")
		)
		(fp_line
			(start 2.567686 -2.567686)
			(end -2.567686 -2.567686)
			(stroke
				(width 0.1524)
				(type default)
			)
			(layer "F.SilkS")
		)
		(fp_line
			(start -2.567686 2.567686)
			(end 2.567686 2.567686)
			(stroke
				(width 0.1524)
				(type default)
			)
			(layer "F.SilkS")
		)
		(fp_line
			(start -2.567686 -2.567686)
			(end -2.567686 2.567686)
			(stroke
				(width 0.1524)
				(type default)
			)
			(layer "F.SilkS")
		)
		(fp_poly
			(pts
				(xy -3.055366 -3.35534) (xy -2.69621 -2.277618) (xy -3.773678 -2.636774)
			)
			(stroke
				(width 0)
				(type default)
			)
			(fill yes)
			(layer "F.SilkS")
		)
		(fp_line
			(start 2.549906 2.549906)
			(end 2.549906 -2.549906)
			(stroke
				(width 0.1)
				(type default)
			)
			(layer "F.Fab")
		)
		(fp_line
			(start 2.549906 -2.549906)
			(end -2.549906 -2.549906)
			(stroke
				(width 0.1)
				(type default)
			)
			(layer "F.Fab")
		)
		(fp_line
			(start -2.549906 2.549906)
			(end 2.549906 2.549906)
			(stroke
				(width 0.1)
				(type default)
			)
			(layer "F.Fab")
		)
		(fp_line
			(start -2.549906 -2.549906)
			(end -2.549906 2.549906)
			(stroke
				(width 0.1)
				(type default)
			)
			(layer "F.Fab")
		)
		(fp_poly
			(pts
				(xy -3.806698 -2.25806) (xy -3.806698 -1.24206) (xy -2.790698 -1.75006)
			)
			(stroke
				(width 0)
				(type default)
			)
			(fill yes)
			(layer "F.Fab")
		)
		(pad "1" smd rect
			(at -2.250186 -1.75006 270)
			(size 0.254 0.3556)
			(layers "F.Cu" "F.Mask" "F.Paste")
			(net "P12V_AUX")
		)
		(pad "2" smd rect
			(at -2.237486 -1.249934 270)
			(size 0.254 0.381)
			(layers "F.Cu" "F.Mask" "F.Paste")
			(net "P12V_AUX")
		)
		(pad "3" smd rect
			(at -2.237486 -0.750062 270)
			(size 0.254 0.381)
			(layers "F.Cu" "F.Mask" "F.Paste")
			(net "HSC_D_OC_1")
		)
		(pad "4" smd rect
			(at -2.237486 -0.249936 270)
			(size 0.254 0.381)
			(layers "F.Cu" "F.Mask" "F.Paste")
			(net "HSC_ON")
		)
		(pad "5" smd rect
			(at -2.237486 0.249936 270)
			(size 0.254 0.381)
			(layers "F.Cu" "F.Mask" "F.Paste")
			(net "HSC_FAULT")
		)
		(pad "6" smd rect
			(at -2.237486 0.750062 270)
			(size 0.254 0.381)
			(layers "F.Cu" "F.Mask" "F.Paste")
			(net "HSC_FLT_TYPE_1")
		)
		(pad "7" smd rect
			(at -2.237486 1.249934 270)
			(size 0.254 0.381)
			(layers "F.Cu" "F.Mask" "F.Paste")
			(net "HSC_NC1_1")
		)
		(pad "8" smd rect
			(at -2.250186 1.75006 270)
			(size 0.254 0.3556)
			(layers "F.Cu" "F.Mask" "F.Paste")
			(net "HSC_MODE_1")
		)
		(pad "9" smd rect
			(at -1.75006 2.250186 180)
			(size 0.254 0.3556)
			(layers "F.Cu" "F.Mask" "F.Paste")
			(net "P12V_PSU")
		)
		(pad "10" smd rect
			(at -1.249934 2.237486 180)
			(size 0.254 0.381)
			(layers "F.Cu" "F.Mask" "F.Paste")
			(net "P12V_PSU")
		)
		(pad "11" smd rect
			(at -0.750062 2.237486 180)
			(size 0.254 0.381)
			(layers "F.Cu" "F.Mask" "F.Paste")
			(net "P12V_PSU")
		)
		(pad "12" smd rect
			(at -0.249936 2.237486 180)
			(size 0.254 0.381)
			(layers "F.Cu" "F.Mask" "F.Paste")
			(net "P12V_PSU")
		)
		(pad "13" smd rect
			(at 0.249936 2.237486 180)
			(size 0.254 0.381)
			(layers "F.Cu" "F.Mask" "F.Paste")
			(net "P12V_PSU")
		)
		(pad "14" smd rect
			(at 0.750062 2.237486 180)
			(size 0.254 0.381)
			(layers "F.Cu" "F.Mask" "F.Paste")
			(net "P12V_PSU")
		)
		(pad "15" smd rect
			(at 1.249934 2.237486 180)
			(size 0.254 0.381)
			(layers "F.Cu" "F.Mask" "F.Paste")
			(net "P12V_PSU")
		)
		(pad "16" smd rect
			(at 1.75006 2.250186 180)
			(size 0.254 0.3556)
			(layers "F.Cu" "F.Mask" "F.Paste")
			(net "P12V_PSU")
		)
		(pad "17" smd rect
			(at 2.250186 1.75006 270)
			(size 0.254 0.3556)
			(layers "F.Cu" "F.Mask" "F.Paste")
			(net "HSC_SCREF_1")
		)
		(pad "18" smd rect
			(at 2.237486 1.249934 270)
			(size 0.254 0.381)
			(layers "F.Cu" "F.Mask" "F.Paste")
			(net "HSC_VTEMP")
		)
		(pad "19" smd rect
			(at 2.237486 0.750062 270)
			(size 0.254 0.381)
			(layers "F.Cu" "F.Mask" "F.Paste")
			(net "HSC_SS")
		)
		(pad "20" smd rect
			(at 2.237486 0.249936 270)
			(size 0.254 0.381)
			(layers "F.Cu" "F.Mask" "F.Paste")
			(net "AGND_HSC")
		)
		(pad "21" smd rect
			(at 2.237486 -0.249936 270)
			(size 0.254 0.381)
			(layers "F.Cu" "F.Mask" "F.Paste")
			(net "HSC_VDD_R_1")
		)
		(pad "22" smd rect
			(at 2.237486 -0.750062 270)
			(size 0.254 0.381)
			(layers "F.Cu" "F.Mask" "F.Paste")
			(net "HSC_IMON")
		)
		(pad "23" smd rect
			(at 2.237486 -1.249934 270)
			(size 0.254 0.381)
			(layers "F.Cu" "F.Mask" "F.Paste")
			(net "HSC_CS_1")
		)
		(pad "24" smd rect
			(at 2.250186 -1.75006 270)
			(size 0.254 0.3556)
			(layers "F.Cu" "F.Mask" "F.Paste")
			(net "HSC_OCREF")
		)
		(pad "25" smd rect
			(at 1.75006 -2.250186 180)
			(size 0.254 0.3556)
			(layers "F.Cu" "F.Mask" "F.Paste")
			(net "P12V_AUX")
		)
		(pad "26" smd rect
			(at 1.249934 -2.237486 180)
			(size 0.254 0.381)
			(layers "F.Cu" "F.Mask" "F.Paste")
			(net "P12V_AUX")
		)
		(pad "27" smd rect
			(at 0.750062 -2.237486 180)
			(size 0.254 0.381)
			(layers "F.Cu" "F.Mask" "F.Paste")
			(net "P12V_AUX")
		)
		(pad "28" smd rect
			(at 0.249936 -2.237486 180)
			(size 0.254 0.381)
			(layers "F.Cu" "F.Mask" "F.Paste")
			(net "P12V_AUX")
		)
		(pad "29" smd rect
			(at -0.249936 -2.237486 180)
			(size 0.254 0.381)
			(layers "F.Cu" "F.Mask" "F.Paste")
			(net "P12V_AUX")
		)
		(pad "30" smd rect
			(at -0.750062 -2.237486 180)
			(size 0.254 0.381)
			(layers "F.Cu" "F.Mask" "F.Paste")
			(net "P12V_AUX")
		)
		(pad "31" smd rect
			(at -1.249934 -2.237486 180)
			(size 0.254 0.381)
			(layers "F.Cu" "F.Mask" "F.Paste")
			(net "P12V_AUX")
		)
		(pad "32" smd rect
			(at -1.75006 -2.250186 180)
			(size 0.254 0.3556)
			(layers "F.Cu" "F.Mask" "F.Paste")
			(net "P12V_AUX")
		)
		(pad "33" smd rect
			(at 0 0 180)
			(size 3.4036 3.4036)
			(layers "F.Cu" "F.Mask" "F.Paste")
			(net "P12V_PSU")
		)
		(zone
			(layer "F.Cu")
			(hatch none 0.5)
			(connect_pads
				(clearance 0)
			)
			(min_thickness 0.25)
			(keepout
				(tracks not_allowed)
				(vias allowed)
				(pads allowed)
				(copperpour not_allowed)
				(footprints allowed)
			)
			(placement
				(enabled no)
				(sheetname "")
			)
			(fill
				(thermal_gap 0.5)
				(thermal_bridge_width 0.5)
				(island_removal_mode 0)
			)
			(polygon
				(pts
					(xy 202.193652 -401.275042) (xy 202.193652 -400.845528) (xy 202.04938 -400.701256) (xy 201.619866 -400.701256)
					(xy 201.619866 -400.726656) (xy 198.724266 -400.726656) (xy 198.724266 -400.701256) (xy 198.15048 -400.701256)
					(xy 198.15048 -401.275042) (xy 198.17588 -401.275042) (xy 198.17588 -404.170642) (xy 198.15048 -404.170642)
					(xy 198.15048 -404.475442) (xy 198.419466 -404.475442) (xy 198.419466 -400.970242) (xy 201.924666 -400.970242)
					(xy 201.924666 -403.230842) (xy 202.168252 -403.230842) (xy 202.168252 -401.275042)
				)
			)
		)
	)
	(footprint ""
		(layer "F.Cu")
		(at 46.350428 -97.808034)
		(property "Reference" "C2043"
			(at 0 0 0)
			(layer "F.SilkS")
			(hide yes)
			(effects
				(font
					(size 1.27 1.27)
				)
			)
		)
		(property "Value" ""
			(at 0 0 0)
			(layer "F.Fab")
			(effects
				(font
					(size 1.27 1.27)
				)
			)
		)
		(duplicate_pad_numbers_are_jumpers no)
		(fp_line
			(start -0.7874 -0.4064)
			(end 0.7874 -0.4064)
			(stroke
				(width 0.1524)
				(type default)
			)
			(layer "F.SilkS")
		)
		(fp_line
			(start -0.7874 0.4064)
			(end -0.7874 -0.4064)
			(stroke
				(width 0.1524)
				(type default)
			)
			(layer "F.SilkS")
		)
		(fp_line
			(start 0.7874 -0.4064)
			(end 0.7874 0.4064)
			(stroke
				(width 0.1524)
				(type default)
			)
			(layer "F.SilkS")
		)
		(fp_line
			(start 0.7874 0.4064)
			(end -0.7874 0.4064)
			(stroke
				(width 0.1524)
				(type default)
			)
			(layer "F.SilkS")
		)
		(fp_line
			(start -0.67945 -0.305054)
			(end -0.12065 -0.305054)
			(stroke
				(width 0.1)
				(type default)
			)
			(layer "F.Fab")
		)
		(fp_line
			(start -0.67945 0.3048)
			(end -0.67945 -0.305054)
			(stroke
				(width 0.1)
				(type default)
			)
			(layer "F.Fab")
		)
		(fp_line
			(start -0.12065 -0.305054)
			(end -0.12065 -0.2794)
			(stroke
				(width 0.1)
				(type default)
			)
			(layer "F.Fab")
		)
		(fp_line
			(start -0.12065 -0.2794)
			(end 0.12065 -0.2794)
			(stroke
				(width 0.1)
				(type default)
			)
			(layer "F.Fab")
		)
		(fp_line
			(start -0.12065 0.2794)
			(end -0.12065 0.3048)
			(stroke
				(width 0.1)
				(type default)
			)
			(layer "F.Fab")
		)
		(fp_line
			(start -0.12065 0.3048)
			(end -0.67945 0.3048)
			(stroke
				(width 0.1)
				(type default)
			)
			(layer "F.Fab")
		)
		(fp_line
			(start 0.120396 0.2794)
			(end -0.12065 0.2794)
			(stroke
				(width 0.1)
				(type default)
			)
			(layer "F.Fab")
		)
		(fp_line
			(start 0.120396 0.3048)
			(end 0.120396 0.2794)
			(stroke
				(width 0.1)
				(type default)
			)
			(layer "F.Fab")
		)
		(fp_line
			(start 0.12065 -0.3048)
			(end 0.67945 -0.3048)
			(stroke
				(width 0.1)
				(type default)
			)
			(layer "F.Fab")
		)
		(fp_line
			(start 0.12065 -0.2794)
			(end 0.12065 -0.3048)
			(stroke
				(width 0.1)
				(type default)
			)
			(layer "F.Fab")
		)
		(fp_line
			(start 0.67945 -0.3048)
			(end 0.67945 0.3048)
			(stroke
				(width 0.1)
				(type default)
			)
			(layer "F.Fab")
		)
		(fp_line
			(start 0.67945 0.3048)
			(end 0.120396 0.3048)
			(stroke
				(width 0.1)
				(type default)
			)
			(layer "F.Fab")
		)
		(pad "1" smd circle
			(at -0.40005 0)
			(size 0 0)
			(layers "F.Cu" "F.Mask" "F.Paste")
			(net "P3V3_ADC_MAM")
		)
		(pad "2" smd circle
			(at 0.40005 0)
			(size 0 0)
			(layers "F.Cu" "F.Mask" "F.Paste")
			(net "GND")
		)
	)
	(footprint ""
		(layer "F.Cu")
		(at 430.600104 -137.542778 180)
		(property "Reference" "R2388"
			(at 0 0 180)
			(layer "F.SilkS")
			(hide yes)
			(effects
				(font
					(size 1.27 1.27)
				)
			)
		)
		(property "Value" ""
			(at 0 0 180)
			(layer "F.Fab")
			(effects
				(font
					(size 1.27 1.27)
				)
			)
		)
		(duplicate_pad_numbers_are_jumpers no)
		(fp_line
			(start 0.7874 0.4064)
			(end -0.7874 0.4064)
			(stroke
				(width 0.1524)
				(type default)
			)
			(layer "F.SilkS")
		)
		(fp_line
			(start 0.7874 -0.4064)
			(end 0.7874 0.4064)
			(stroke
				(width 0.1524)
				(type default)
			)
			(layer "F.SilkS")
		)
		(fp_line
			(start -0.7874 0.4064)
			(end -0.7874 -0.4064)
			(stroke
				(width 0.1524)
				(type default)
			)
			(layer "F.SilkS")
		)
		(fp_line
			(start -0.7874 -0.4064)
			(end 0.7874 -0.4064)
			(stroke
				(width 0.1524)
				(type default)
			)
			(layer "F.SilkS")
		)
		(fp_line
			(start 0.67945 0.3048)
			(end 0.120396 0.3048)
			(stroke
				(width 0.1)
				(type default)
			)
			(layer "F.Fab")
		)
		(fp_line
			(start 0.67945 -0.3048)
			(end 0.67945 0.3048)
			(stroke
				(width 0.1)
				(type default)
			)
			(layer "F.Fab")
		)
		(fp_line
			(start 0.12065 -0.2794)
			(end 0.12065 -0.3048)
			(stroke
				(width 0.1)
				(type default)
			)
			(layer "F.Fab")
		)
		(fp_line
			(start 0.12065 -0.3048)
			(end 0.67945 -0.3048)
			(stroke
				(width 0.1)
				(type default)
			)
			(layer "F.Fab")
		)
		(fp_line
			(start 0.120396 0.3048)
			(end 0.120396 0.2794)
			(stroke
				(width 0.1)
				(type default)
			)
			(layer "F.Fab")
		)
		(fp_line
			(start 0.120396 0.2794)
			(end -0.12065 0.2794)
			(stroke
				(width 0.1)
				(type default)
			)
			(layer "F.Fab")
		)
		(fp_line
			(start -0.12065 0.3048)
			(end -0.67945 0.3048)
			(stroke
				(width 0.1)
				(type default)
			)
			(layer "F.Fab")
		)
		(fp_line
			(start -0.12065 0.2794)
			(end -0.12065 0.3048)
			(stroke
				(width 0.1)
				(type default)
			)
			(layer "F.Fab")
		)
		(fp_line
			(start -0.12065 -0.2794)
			(end 0.12065 -0.2794)
			(stroke
				(width 0.1)
				(type default)
			)
			(layer "F.Fab")
		)
		(fp_line
			(start -0.12065 -0.305054)
			(end -0.12065 -0.2794)
			(stroke
				(width 0.1)
				(type default)
			)
			(layer "F.Fab")
		)
		(fp_line
			(start -0.67945 0.3048)
			(end -0.67945 -0.305054)
			(stroke
				(width 0.1)
				(type default)
			)
			(layer "F.Fab")
		)
		(fp_line
			(start -0.67945 -0.305054)
			(end -0.12065 -0.305054)
			(stroke
				(width 0.1)
				(type default)
			)
			(layer "F.Fab")
		)
		(pad "1" smd circle
			(at -0.40005 0 180)
			(size 0 0)
			(layers "F.Cu" "F.Mask" "F.Paste")
			(net "SVID_DIO0_CPU0_R")
		)
		(pad "2" smd circle
			(at 0.40005 0 180)
			(size 0 0)
			(layers "F.Cu" "F.Mask" "F.Paste")
			(net "SVID_DIO_PVCCINFAON_CPU0_R")
		)
	)
	(footprint ""
		(layer "F.Cu")
		(at 307.93309 -427.170342)
		(property "Reference" "R4266"
			(at 0 0 0)
			(layer "F.SilkS")
			(hide yes)
			(effects
				(font
					(size 1.27 1.27)
				)
			)
		)
		(property "Value" ""
			(at 0 0 0)
			(layer "F.Fab")
			(effects
				(font
					(size 1.27 1.27)
				)
			)
		)
		(duplicate_pad_numbers_are_jumpers no)
		(fp_line
			(start -0.7874 -0.4064)
			(end 0.7874 -0.4064)
			(stroke
				(width 0.1524)
				(type default)
			)
			(layer "F.SilkS")
		)
		(fp_line
			(start -0.7874 0.4064)
			(end -0.7874 -0.4064)
			(stroke
				(width 0.1524)
				(type default)
			)
			(layer "F.SilkS")
		)
		(fp_line
			(start 0.7874 -0.4064)
			(end 0.7874 0.4064)
			(stroke
				(width 0.1524)
				(type default)
			)
			(layer "F.SilkS")
		)
		(fp_line
			(start 0.7874 0.4064)
			(end -0.7874 0.4064)
			(stroke
				(width 0.1524)
				(type default)
			)
			(layer "F.SilkS")
		)
		(fp_line
			(start -0.67945 -0.305054)
			(end -0.12065 -0.305054)
			(stroke
				(width 0.1)
				(type default)
			)
			(layer "F.Fab")
		)
		(fp_line
			(start -0.67945 0.3048)
			(end -0.67945 -0.305054)
			(stroke
				(width 0.1)
				(type default)
			)
			(layer "F.Fab")
		)
		(fp_line
			(start -0.12065 -0.305054)
			(end -0.12065 -0.2794)
			(stroke
				(width 0.1)
				(type default)
			)
			(layer "F.Fab")
		)
		(fp_line
			(start -0.12065 -0.2794)
			(end 0.12065 -0.2794)
			(stroke
				(width 0.1)
				(type default)
			)
			(layer "F.Fab")
		)
		(fp_line
			(start -0.12065 0.2794)
			(end -0.12065 0.3048)
			(stroke
				(width 0.1)
				(type default)
			)
			(layer "F.Fab")
		)
		(fp_line
			(start -0.12065 0.3048)
			(end -0.67945 0.3048)
			(stroke
				(width 0.1)
				(type default)
			)
			(layer "F.Fab")
		)
		(fp_line
			(start 0.120396 0.2794)
			(end -0.12065 0.2794)
			(stroke
				(width 0.1)
				(type default)
			)
			(layer "F.Fab")
		)
		(fp_line
			(start 0.120396 0.3048)
			(end 0.120396 0.2794)
			(stroke
				(width 0.1)
				(type default)
			)
			(layer "F.Fab")
		)
		(fp_line
			(start 0.12065 -0.3048)
			(end 0.67945 -0.3048)
			(stroke
				(width 0.1)
				(type default)
			)
			(layer "F.Fab")
		)
		(fp_line
			(start 0.12065 -0.2794)
			(end 0.12065 -0.3048)
			(stroke
				(width 0.1)
				(type default)
			)
			(layer "F.Fab")
		)
		(fp_line
			(start 0.67945 -0.3048)
			(end 0.67945 0.3048)
			(stroke
				(width 0.1)
				(type default)
			)
			(layer "F.Fab")
		)
		(fp_line
			(start 0.67945 0.3048)
			(end 0.120396 0.3048)
			(stroke
				(width 0.1)
				(type default)
			)
			(layer "F.Fab")
		)
		(pad "1" smd circle
			(at -0.40005 0)
			(size 0 0)
			(layers "F.Cu" "F.Mask" "F.Paste")
			(net "PWRGD_P3V3_AUX_PDB_BUF_R")
		)
		(pad "2" smd circle
			(at 0.40005 0)
			(size 0 0)
			(layers "F.Cu" "F.Mask" "F.Paste")
			(net "PWRGD_P3V3_AUX_PDB_BUF")
		)
	)
)
